FILE_TYPE = CONNECTIVITY;
{Allegro Design Entry HDL 17.2-2016 S081 (4005846) 1/11/2022}
"PAGE_NUMBER" = 24;
0"NC";
1"M_E_CPU0_SA_CA<6:0>";
2"M_E_CPU0_SA_CS_N<3:0>";
3"M_E_CPU0_SA_DQS_DN<9:0>";
4"M_E_CPU0_SA_DQS_DP<9:0>";
5"M_E_CPU0_SB_CA<6:0>";
6"M_E_CPU0_SB_CS_N<3:0>";
7"M_E_CPU0_SB_DQS_DN<9:0>";
8"M_E_CPU0_SB_DQS_DP<9:0>";
9"M_E_CPU0_SB_CB<7:0>";
10"M_E_CPU0_SB_DQ<31:0>";
11"M_E_CPU0_SA_CB<7:0>";
12"M_E_CPU0_SA_DQ<31:0>";
13"M_E_CPU0_CLK_DP<1:0>";
14"M_E_CPU0_CLK_DN<1:0>";
15"M_E_CPU0_SA_DQ<21>";
16"M_E_CPU0_SA_DQ<20>";
17"M_E_CPU0_SA_DQ<19>";
18"M_E_CPU0_SB_DQ<24>";
19"M_E_CPU0_SB_DQ<25>";
20"M_E_CPU0_SB_DQ<26>";
21"M_E_CPU0_SB_DQ<27>";
22"M_E_CPU0_SB_DQ<28>";
23"M_E_CPU0_CLK_DN<1>";
24"M_E_CPU0_CLK_DN<0>";
25"M_E_CPU0_CLK_DP<1>";
26"M_E_CPU0_CLK_DP<0>";
27"M_E_CPU0_SA_DQ<31>";
28"M_E_CPU0_SA_DQ<30>";
29"M_E_CPU0_SA_DQ<29>";
30"M_E_CPU0_SA_DQ<28>";
31"M_E_CPU0_SA_DQ<27>";
32"M_E_CPU0_SA_DQ<26>";
33"M_E_CPU0_SA_DQ<25>";
34"M_E_CPU0_SA_DQ<24>";
35"M_E_CPU0_SA_DQ<23>";
36"M_E_CPU0_SA_DQ<22>";
37"M_E_CPU0_SA_DQ<18>";
38"M_E_CPU0_SA_DQ<17>";
39"M_E_CPU0_SA_DQ<16>";
40"M_E_CPU0_SA_DQ<15>";
41"M_E_CPU0_SA_DQ<14>";
42"M_E_CPU0_SA_DQ<13>";
43"M_E_CPU0_SA_DQ<12>";
44"M_E_CPU0_SA_DQ<11>";
45"M_E_CPU0_SA_DQ<10>";
46"M_E_CPU0_SA_DQ<9>";
47"M_E_CPU0_SA_DQ<8>";
48"M_E_CPU0_SA_DQ<7>";
49"M_E_CPU0_SA_DQ<6>";
50"M_E_CPU0_SA_DQ<5>";
51"M_E_CPU0_SA_DQ<4>";
52"M_E_CPU0_SA_DQ<3>";
53"M_E_CPU0_SA_DQ<2>";
54"M_E_CPU0_SA_DQ<1>";
55"M_E_CPU0_SA_DQ<0>";
56"M_E_CPU0_SA_CB<7>";
57"M_E_CPU0_SA_CB<6>";
58"M_E_CPU0_SA_CB<5>";
59"M_E_CPU0_SA_CB<4>";
60"M_E_CPU0_SA_CB<3>";
61"M_E_CPU0_SA_CB<2>";
62"M_E_CPU0_SA_CB<1>";
63"M_E_CPU0_SA_CB<0>";
64"M_E_CPU0_SB_DQ<31>";
65"M_E_CPU0_SB_DQ<30>";
66"M_E_CPU0_SB_DQ<29>";
67"M_E_CPU0_SB_DQ<23>";
68"M_E_CPU0_SB_DQ<22>";
69"M_E_CPU0_SB_DQ<21>";
70"M_E_CPU0_SB_DQ<20>";
71"M_E_CPU0_SB_DQ<19>";
72"M_E_CPU0_SB_DQ<18>";
73"M_E_CPU0_SB_DQ<17>";
74"M_E_CPU0_SB_DQ<16>";
75"M_E_CPU0_SB_DQ<15>";
76"M_E_CPU0_SB_DQ<14>";
77"M_E_CPU0_SB_DQ<13>";
78"M_E_CPU0_SB_DQ<12>";
79"M_E_CPU0_SB_DQ<11>";
80"M_E_CPU0_SB_DQ<10>";
81"M_E_CPU0_SB_DQ<9>";
82"M_E_CPU0_SB_DQ<8>";
83"M_E_CPU0_SB_DQ<7>";
84"M_E_CPU0_SB_DQ<6>";
85"M_E_CPU0_SB_DQ<5>";
86"M_E_CPU0_SB_DQ<4>";
87"M_E_CPU0_SB_DQ<3>";
88"M_E_CPU0_SB_DQ<2>";
89"M_E_CPU0_SB_DQ<1>";
90"M_E_CPU0_SB_DQ<0>";
91"M_E_CPU0_SB_CB<7>";
92"M_E_CPU0_SB_CB<6>";
93"M_E_CPU0_SB_CB<5>";
94"M_E_CPU0_SB_CB<4>";
95"M_E_CPU0_SB_CB<3>";
96"M_E_CPU0_SB_CB<2>";
97"M_E_CPU0_SB_CB<1>";
98"M_E_CPU0_SB_CB<0>";
99"M_E_CPU0_SB_PAR";
100"M_E_CPU0_SB_DQS_DP<0>";
101"M_E_CPU0_SB_DQS_DP<1>";
102"M_E_CPU0_SB_DQS_DP<2>";
103"M_E_CPU0_SB_DQS_DP<3>";
104"M_E_CPU0_SB_DQS_DP<4>";
105"M_E_CPU0_SB_DQS_DP<5>";
106"M_E_CPU0_SB_DQS_DP<6>";
107"M_E_CPU0_SB_DQS_DP<7>";
108"M_E_CPU0_SB_DQS_DP<8>";
109"M_E_CPU0_SB_DQS_DP<9>";
110"M_E_CPU0_SB_DQS_DN<0>";
111"M_E_CPU0_SB_DQS_DN<1>";
112"M_E_CPU0_SB_DQS_DN<2>";
113"M_E_CPU0_SB_DQS_DN<3>";
114"M_E_CPU0_SB_DQS_DN<4>";
115"M_E_CPU0_SB_DQS_DN<5>";
116"M_E_CPU0_SB_DQS_DN<6>";
117"M_E_CPU0_SB_DQS_DN<7>";
118"M_E_CPU0_SB_DQS_DN<8>";
119"M_E_CPU0_SB_DQS_DN<9>";
120"M_E_CPU0_SB_CS_N<0>";
121"M_E_CPU0_SB_CS_N<1>";
122"M_E_CPU0_SB_CS_N<2>";
123"M_E_CPU0_SB_CS_N<3>";
124"M_E_CPU0_SB_CA<0>";
125"M_E_CPU0_SB_CA<1>";
126"M_E_CPU0_SB_CA<2>";
127"M_E_CPU0_SB_CA<3>";
128"M_E_CPU0_SB_CA<4>";
129"M_E_CPU0_SB_CA<5>";
130"M_E_CPU0_SB_CA<6>";
131"M_E_CPU0_SA_PAR";
132"M_E_CPU0_SA_DQS_DP<0>";
133"M_E_CPU0_SA_DQS_DP<1>";
134"M_E_CPU0_SA_DQS_DP<2>";
135"M_E_CPU0_SA_DQS_DP<3>";
136"M_E_CPU0_SA_DQS_DP<4>";
137"M_E_CPU0_SA_DQS_DP<5>";
138"M_E_CPU0_SA_DQS_DP<6>";
139"M_E_CPU0_SA_DQS_DP<7>";
140"M_E_CPU0_SA_DQS_DP<8>";
141"M_E_CPU0_SA_DQS_DP<9>";
142"M_E_CPU0_SA_DQS_DN<0>";
143"M_E_CPU0_SA_DQS_DN<1>";
144"M_E_CPU0_SA_DQS_DN<2>";
145"M_E_CPU0_SA_DQS_DN<3>";
146"M_E_CPU0_SA_DQS_DN<4>";
147"M_E_CPU0_SA_DQS_DN<5>";
148"M_E_CPU0_SA_DQS_DN<6>";
149"M_E_CPU0_SA_DQS_DN<7>";
150"M_E_CPU0_SA_DQS_DN<8>";
151"M_E_CPU0_SA_DQS_DN<9>";
152"M_E_CPU0_SA_CS_N<0>";
153"M_E_CPU0_SA_CS_N<1>";
154"M_E_CPU0_SA_CS_N<2>";
155"M_E_CPU0_SA_CS_N<3>";
156"M_E_CPU0_SA_CA<0>";
157"M_E_CPU0_SA_CA<1>";
158"M_E_CPU0_SA_CA<2>";
159"M_E_CPU0_SA_CA<3>";
160"M_E_CPU0_SA_CA<4>";
161"M_E_CPU0_SA_CA<5>";
162"M_E_CPU0_SA_CA<6>";
163"M_E_CPU0_SB_RSP<0>";
164"M_E_CPU0_SB_RSP<1>";
165"M_E_CPU0_SA_RSP<0>";
166"M_E_CPU0_SA_RSP<1>";
167"M_E_CPU0_ALERT_N";
%"TAP"
"1","(2725,400)","0","standard","I100";
;
CDS_LIB"standard"
BODY_TYPE"PLUMBING"
HDL_TAP"TRUE";
"B \NAC \NWC"6;
"S \NAC"
BN"3"123;
%"TAP"
"1","(2725,600)","0","standard","I101";
;
CDS_LIB"standard"
BODY_TYPE"PLUMBING"
HDL_TAP"TRUE";
"B \NAC \NWC"2;
"S \NAC"
BN"1"153;
%"TAP"
"1","(2725,550)","0","standard","I102";
;
CDS_LIB"standard"
BODY_TYPE"PLUMBING"
HDL_TAP"TRUE";
"B \NAC \NWC"2;
"S \NAC"
BN"0"152;
%"TAP"
"1","(2725,650)","0","standard","I103";
;
CDS_LIB"standard"
BODY_TYPE"PLUMBING"
HDL_TAP"TRUE";
"B \NAC \NWC"2;
"S \NAC"
BN"2"154;
%"TAP"
"1","(2725,700)","0","standard","I104";
;
CDS_LIB"standard"
BODY_TYPE"PLUMBING"
HDL_TAP"TRUE";
"B \NAC \NWC"2;
"S \NAC"
BN"3"155;
%"TAP"
"1","(2725,950)","0","standard","I105";
;
CDS_LIB"standard"
BODY_TYPE"PLUMBING"
HDL_TAP"TRUE";
"B \NAC \NWC"5;
"S \NAC"
BN"1"125;
%"TAP"
"1","(2725,900)","0","standard","I106";
;
CDS_LIB"standard"
BODY_TYPE"PLUMBING"
HDL_TAP"TRUE";
"B \NAC \NWC"5;
"S \NAC"
BN"0"124;
%"TAP"
"1","(2725,1050)","0","standard","I107";
;
CDS_LIB"standard"
BODY_TYPE"PLUMBING"
HDL_TAP"TRUE";
"B \NAC \NWC"5;
"S \NAC"
BN"3"127;
%"TAP"
"1","(2725,1100)","0","standard","I108";
;
CDS_LIB"standard"
BODY_TYPE"PLUMBING"
HDL_TAP"TRUE";
"B \NAC \NWC"5;
"S \NAC"
BN"4"128;
%"TAP"
"1","(2725,1000)","0","standard","I109";
;
CDS_LIB"standard"
BODY_TYPE"PLUMBING"
HDL_TAP"TRUE";
"B \NAC \NWC"5;
"S \NAC"
BN"2"126;
%"TAP"
"1","(-700,150)","2","standard","I11";
;
CDS_LIB"standard"
BODY_TYPE"PLUMBING"
HDL_TAP"TRUE";
"B \NAC \NWC"9;
"S \NAC"
BN"2"96;
%"TAP"
"1","(2725,1200)","0","standard","I110";
;
CDS_LIB"standard"
BODY_TYPE"PLUMBING"
HDL_TAP"TRUE";
"B \NAC \NWC"5;
"S \NAC"
BN"6"130;
%"TAP"
"1","(2725,1150)","0","standard","I111";
;
CDS_LIB"standard"
BODY_TYPE"PLUMBING"
HDL_TAP"TRUE";
"B \NAC \NWC"5;
"S \NAC"
BN"5"129;
%"TAP"
"1","(2725,1400)","0","standard","I112";
;
CDS_LIB"standard"
BODY_TYPE"PLUMBING"
HDL_TAP"TRUE";
"B \NAC \NWC"1;
"S \NAC"
BN"0"156;
%"TAP"
"1","(2725,1450)","0","standard","I113";
;
CDS_LIB"standard"
BODY_TYPE"PLUMBING"
HDL_TAP"TRUE";
"B \NAC \NWC"1;
"S \NAC"
BN"1"157;
%"TAP"
"1","(2725,1500)","0","standard","I114";
;
CDS_LIB"standard"
BODY_TYPE"PLUMBING"
HDL_TAP"TRUE";
"B \NAC \NWC"1;
"S \NAC"
BN"2"158;
%"TAP"
"1","(2725,1600)","0","standard","I115";
;
CDS_LIB"standard"
BODY_TYPE"PLUMBING"
HDL_TAP"TRUE";
"B \NAC \NWC"1;
"S \NAC"
BN"4"160;
%"TAP"
"1","(2725,1550)","0","standard","I116";
;
CDS_LIB"standard"
BODY_TYPE"PLUMBING"
HDL_TAP"TRUE";
"B \NAC \NWC"1;
"S \NAC"
BN"3"159;
%"TAP"
"1","(2725,1700)","0","standard","I117";
;
CDS_LIB"standard"
BODY_TYPE"PLUMBING"
HDL_TAP"TRUE";
"B \NAC \NWC"1;
"S \NAC"
BN"6"162;
%"TAP"
"1","(2725,1650)","0","standard","I118";
;
CDS_LIB"standard"
BODY_TYPE"PLUMBING"
HDL_TAP"TRUE";
"B \NAC \NWC"1;
"S \NAC"
BN"5"161;
%"TAP"
"1","(2725,1850)","0","standard","I119";
;
CDS_LIB"standard"
BODY_TYPE"PLUMBING"
HDL_TAP"TRUE";
"B \NAC \NWC"7;
"S \NAC"
BN"0"110;
%"TAP"
"1","(-700,200)","2","standard","I12";
;
CDS_LIB"standard"
BODY_TYPE"PLUMBING"
HDL_TAP"TRUE";
"B \NAC \NWC"9;
"S \NAC"
BN"3"95;
%"TAP"
"1","(2725,1950)","0","standard","I120";
;
CDS_LIB"standard"
BODY_TYPE"PLUMBING"
HDL_TAP"TRUE";
"B \NAC \NWC"7;
"S \NAC"
BN"2"112;
%"TAP"
"1","(2725,2000)","0","standard","I121";
;
CDS_LIB"standard"
BODY_TYPE"PLUMBING"
HDL_TAP"TRUE";
"B \NAC \NWC"7;
"S \NAC"
BN"3"113;
%"TAP"
"1","(2725,1900)","0","standard","I122";
;
CDS_LIB"standard"
BODY_TYPE"PLUMBING"
HDL_TAP"TRUE";
"B \NAC \NWC"7;
"S \NAC"
BN"1"111;
%"TAP"
"1","(2725,2100)","0","standard","I123";
;
CDS_LIB"standard"
BODY_TYPE"PLUMBING"
HDL_TAP"TRUE";
"B \NAC \NWC"7;
"S \NAC"
BN"5"115;
%"TAP"
"1","(2725,2050)","0","standard","I124";
;
CDS_LIB"standard"
BODY_TYPE"PLUMBING"
HDL_TAP"TRUE";
"B \NAC \NWC"7;
"S \NAC"
BN"4"114;
%"TAP"
"1","(2725,2200)","0","standard","I125";
;
CDS_LIB"standard"
BODY_TYPE"PLUMBING"
HDL_TAP"TRUE";
"B \NAC \NWC"7;
"S \NAC"
BN"7"117;
%"TAP"
"1","(2725,2250)","0","standard","I126";
;
CDS_LIB"standard"
BODY_TYPE"PLUMBING"
HDL_TAP"TRUE";
"B \NAC \NWC"7;
"S \NAC"
BN"8"118;
%"TAP"
"1","(2725,2150)","0","standard","I127";
;
CDS_LIB"standard"
BODY_TYPE"PLUMBING"
HDL_TAP"TRUE";
"B \NAC \NWC"7;
"S \NAC"
BN"6"116;
%"TAP"
"1","(2725,2400)","0","standard","I128";
;
CDS_LIB"standard"
BODY_TYPE"PLUMBING"
HDL_TAP"TRUE";
"B \NAC \NWC"8;
"S \NAC"
BN"0"100;
%"TAP"
"1","(2725,2300)","0","standard","I129";
;
CDS_LIB"standard"
BODY_TYPE"PLUMBING"
HDL_TAP"TRUE";
"B \NAC \NWC"7;
"S \NAC"
BN"9"119;
%"TAP"
"1","(-700,250)","2","standard","I13";
;
CDS_LIB"standard"
BODY_TYPE"PLUMBING"
HDL_TAP"TRUE";
"B \NAC \NWC"9;
"S \NAC"
BN"4"94;
%"TAP"
"1","(2725,2450)","0","standard","I130";
;
CDS_LIB"standard"
BODY_TYPE"PLUMBING"
HDL_TAP"TRUE";
"B \NAC \NWC"8;
"S \NAC"
BN"1"101;
%"TAP"
"1","(2725,2500)","0","standard","I131";
;
CDS_LIB"standard"
BODY_TYPE"PLUMBING"
HDL_TAP"TRUE";
"B \NAC \NWC"8;
"S \NAC"
BN"2"102;
%"TAP"
"1","(2725,2600)","0","standard","I132";
;
CDS_LIB"standard"
BODY_TYPE"PLUMBING"
HDL_TAP"TRUE";
"B \NAC \NWC"8;
"S \NAC"
BN"4"104;
%"TAP"
"1","(2725,2650)","0","standard","I133";
;
CDS_LIB"standard"
BODY_TYPE"PLUMBING"
HDL_TAP"TRUE";
"B \NAC \NWC"8;
"S \NAC"
BN"5"105;
%"TAP"
"1","(2725,2550)","0","standard","I134";
;
CDS_LIB"standard"
BODY_TYPE"PLUMBING"
HDL_TAP"TRUE";
"B \NAC \NWC"8;
"S \NAC"
BN"3"103;
%"TAP"
"1","(2725,2700)","0","standard","I135";
;
CDS_LIB"standard"
BODY_TYPE"PLUMBING"
HDL_TAP"TRUE";
"B \NAC \NWC"8;
"S \NAC"
BN"6"106;
%"TAP"
"1","(2725,2750)","0","standard","I136";
;
CDS_LIB"standard"
BODY_TYPE"PLUMBING"
HDL_TAP"TRUE";
"B \NAC \NWC"8;
"S \NAC"
BN"7"107;
%"TAP"
"1","(2725,2850)","0","standard","I137";
;
CDS_LIB"standard"
BODY_TYPE"PLUMBING"
HDL_TAP"TRUE";
"B \NAC \NWC"8;
"S \NAC"
BN"9"109;
%"TAP"
"1","(2725,2800)","0","standard","I138";
;
CDS_LIB"standard"
BODY_TYPE"PLUMBING"
HDL_TAP"TRUE";
"B \NAC \NWC"8;
"S \NAC"
BN"8"108;
%"TAP"
"1","(2725,3000)","0","standard","I139";
;
CDS_LIB"standard"
BODY_TYPE"PLUMBING"
HDL_TAP"TRUE";
"B \NAC \NWC"3;
"S \NAC"
BN"0"142;
%"TAP"
"1","(-700,300)","2","standard","I14";
;
CDS_LIB"standard"
BODY_TYPE"PLUMBING"
HDL_TAP"TRUE";
"B \NAC \NWC"9;
"S \NAC"
BN"5"93;
%"TAP"
"1","(2725,3100)","0","standard","I140";
;
CDS_LIB"standard"
BODY_TYPE"PLUMBING"
HDL_TAP"TRUE";
"B \NAC \NWC"3;
"S \NAC"
BN"2"144;
%"TAP"
"1","(2725,3150)","0","standard","I141";
;
CDS_LIB"standard"
BODY_TYPE"PLUMBING"
HDL_TAP"TRUE";
"B \NAC \NWC"3;
"S \NAC"
BN"3"145;
%"TAP"
"1","(2725,3050)","0","standard","I142";
;
CDS_LIB"standard"
BODY_TYPE"PLUMBING"
HDL_TAP"TRUE";
"B \NAC \NWC"3;
"S \NAC"
BN"1"143;
%"TAP"
"1","(2725,3200)","0","standard","I143";
;
CDS_LIB"standard"
BODY_TYPE"PLUMBING"
HDL_TAP"TRUE";
"B \NAC \NWC"3;
"S \NAC"
BN"4"146;
%"TAP"
"1","(2725,3250)","0","standard","I144";
;
CDS_LIB"standard"
BODY_TYPE"PLUMBING"
HDL_TAP"TRUE";
"B \NAC \NWC"3;
"S \NAC"
BN"5"147;
%"TAP"
"1","(2725,3300)","0","standard","I145";
;
CDS_LIB"standard"
BODY_TYPE"PLUMBING"
HDL_TAP"TRUE";
"B \NAC \NWC"3;
"S \NAC"
BN"6"148;
%"TAP"
"1","(2725,3400)","0","standard","I146";
;
CDS_LIB"standard"
BODY_TYPE"PLUMBING"
HDL_TAP"TRUE";
"B \NAC \NWC"3;
"S \NAC"
BN"8"150;
%"TAP"
"1","(2725,3350)","0","standard","I147";
;
CDS_LIB"standard"
BODY_TYPE"PLUMBING"
HDL_TAP"TRUE";
"B \NAC \NWC"3;
"S \NAC"
BN"7"149;
%"TAP"
"1","(2725,3550)","0","standard","I148";
;
CDS_LIB"standard"
BODY_TYPE"PLUMBING"
HDL_TAP"TRUE";
"B \NAC \NWC"4;
"S \NAC"
BN"0"132;
%"TAP"
"1","(2725,3450)","0","standard","I149";
;
CDS_LIB"standard"
BODY_TYPE"PLUMBING"
HDL_TAP"TRUE";
"B \NAC \NWC"3;
"S \NAC"
BN"9"151;
%"TAP"
"1","(-700,350)","2","standard","I15";
;
CDS_LIB"standard"
BODY_TYPE"PLUMBING"
HDL_TAP"TRUE";
"B \NAC \NWC"9;
"S \NAC"
BN"6"92;
%"TAP"
"1","(2725,3650)","0","standard","I150";
;
CDS_LIB"standard"
BODY_TYPE"PLUMBING"
HDL_TAP"TRUE";
"B \NAC \NWC"4;
"S \NAC"
BN"2"134;
%"TAP"
"1","(2725,3600)","0","standard","I151";
;
CDS_LIB"standard"
BODY_TYPE"PLUMBING"
HDL_TAP"TRUE";
"B \NAC \NWC"4;
"S \NAC"
BN"1"133;
%"TAP"
"1","(2725,3750)","0","standard","I152";
;
CDS_LIB"standard"
BODY_TYPE"PLUMBING"
HDL_TAP"TRUE";
"B \NAC \NWC"4;
"S \NAC"
BN"4"136;
%"TAP"
"1","(2725,3800)","0","standard","I153";
;
CDS_LIB"standard"
BODY_TYPE"PLUMBING"
HDL_TAP"TRUE";
"B \NAC \NWC"4;
"S \NAC"
BN"5"137;
%"TAP"
"1","(2725,3700)","0","standard","I154";
;
CDS_LIB"standard"
BODY_TYPE"PLUMBING"
HDL_TAP"TRUE";
"B \NAC \NWC"4;
"S \NAC"
BN"3"135;
%"TAP"
"1","(2725,3900)","0","standard","I155";
;
CDS_LIB"standard"
BODY_TYPE"PLUMBING"
HDL_TAP"TRUE";
"B \NAC \NWC"4;
"S \NAC"
BN"7"139;
%"TAP"
"1","(2725,3850)","0","standard","I156";
;
CDS_LIB"standard"
BODY_TYPE"PLUMBING"
HDL_TAP"TRUE";
"B \NAC \NWC"4;
"S \NAC"
BN"6"138;
%"TAP"
"1","(2725,4000)","0","standard","I157";
;
CDS_LIB"standard"
BODY_TYPE"PLUMBING"
HDL_TAP"TRUE";
"B \NAC \NWC"4;
"S \NAC"
BN"9"141;
%"TAP"
"1","(2725,3950)","0","standard","I158";
;
CDS_LIB"standard"
BODY_TYPE"PLUMBING"
HDL_TAP"TRUE";
"B \NAC \NWC"4;
"S \NAC"
BN"8"140;
%"TAP"
"1","(-700,400)","2","standard","I16";
;
CDS_LIB"standard"
BODY_TYPE"PLUMBING"
HDL_TAP"TRUE";
"B \NAC \NWC"9;
"S \NAC"
BN"7"91;
%"SOCKET4677_AZIF0045P001C01CS"
"12","(1025,1900)","0","pure_quanta","I169";
;
PART_NUMBER"DGA^7000023"
PART_TYPE"SMLF"
MATERIAL"IO"
VALUE"SOCKET4677_AZIF0045-P001C01CS"
$LOCATION"U2"
CDS_LIB"pure_quanta"
NEEDS_NO_SIZE"TRUE"
CDS_LMAN_SYM_OUTLINE"-1100,2250,1050,-2250"
CDS_LOCATION"U2"
$SEC"12"
CDS_SEC"12";
"DDR4_SB_PAR"
$PN"EP42"99;
"DDR4_SB_ECC0"
$PN"EL35"98;
"DDR4_SB_ECC1"
$PN"EM34"97;
"DDR4_SB_ECC2"
$PN"ER35"96;
"DDR4_SB_ECC3"
$PN"EP34"95;
"DDR4_SB_ECC4"
$PN"EM38"94;
"DDR4_SB_ECC5"
$PN"EL37"93;
"DDR4_SB_ECC6"
$PN"EP38"92;
"DDR4_SB_ECC7"
$PN"ER37"91;
"DDR4_SB_DQS_DP0"
$PN"EC27"100;
"DDR4_SB_DQS_DP1"
$PN"EM30"101;
"DDR4_SB_DQS_DP2"
$PN"EM24"102;
"DDR4_SB_DQS_DP3"
$PN"EM18"103;
"DDR4_SB_DQS_DP4"
$PN"EP36"104;
"DDR4_SB_DQS_DP5"
$PN"EG27"105;
"DDR4_SB_DQS_DP6"
$PN"EP30"106;
"DDR4_SB_DQS_DP7"
$PN"EP24"107;
"DDR4_SB_DQS_DP8"
$PN"EP18"108;
"DDR4_SB_DQS_DP9"
$PN"EM36"109;
"DDR4_SB_DQS_DN0 \B"
$PN"EE27"110;
"DDR4_SB_DQS_DN1 \B"
$PN"EK30"111;
"DDR4_SB_DQS_DN2 \B"
$PN"EK24"112;
"DDR4_SB_DQS_DN3 \B"
$PN"EK18"113;
"DDR4_SB_DQS_DN4 \B"
$PN"ET36"114;
"DDR4_SB_DQS_DN5 \B"
$PN"EJ27"115;
"DDR4_SB_DQS_DN6 \B"
$PN"ET30"116;
"DDR4_SB_DQS_DN7 \B"
$PN"ET24"117;
"DDR4_SB_DQS_DN8 \B"
$PN"ET18"118;
"DDR4_SB_DQS_DN9 \B"
$PN"EK36"119;
"DDR4_SB_DQ0"
$PN"EE29"90;
"DDR4_SB_DQ1"
$PN"ED28"89;
"DDR4_SB_DQ2"
$PN"EG29"88;
"DDR4_SB_DQ3"
$PN"EH28"87;
"DDR4_SB_DQ4"
$PN"ED26"86;
"DDR4_SB_DQ5"
$PN"EE25"85;
"DDR4_SB_DQ6"
$PN"EH26"84;
"DDR4_SB_DQ7"
$PN"EG25"83;
"DDR4_SB_DQ8"
$PN"EM32"82;
"DDR4_SB_DQ9"
$PN"EL31"81;
"DDR4_SB_DQ10"
$PN"EP32"80;
"DDR4_SB_DQ11"
$PN"ER31"79;
"DDR4_SB_DQ12"
$PN"EL29"78;
"DDR4_SB_DQ13"
$PN"EM28"77;
"DDR4_SB_DQ14"
$PN"ER29"76;
"DDR4_SB_DQ15"
$PN"EP28"75;
"DDR4_SB_DQ16"
$PN"EM26"74;
"DDR4_SB_DQ17"
$PN"EL25"73;
"DDR4_SB_DQ18"
$PN"EP26"72;
"DDR4_SB_DQ19"
$PN"ER25"71;
"DDR4_SB_DQ20"
$PN"EL23"70;
"DDR4_SB_DQ21"
$PN"EM22"69;
"DDR4_SB_DQ22"
$PN"ER23"68;
"DDR4_SB_DQ23"
$PN"EP22"67;
"DDR4_SB_DQ24"
$PN"EM20"18;
"DDR4_SB_DQ25"
$PN"EL19"19;
"DDR4_SB_DQ26"
$PN"EP20"20;
"DDR4_SB_DQ27"
$PN"ER19"21;
"DDR4_SB_DQ28"
$PN"EL17"22;
"DDR4_SB_DQ29"
$PN"EM16"66;
"DDR4_SB_DQ30"
$PN"ER17"65;
"DDR4_SB_DQ31"
$PN"EP16"64;
"DDR4_SB_CS_N0 \B"
$PN"EP40"120;
"DDR4_SB_CS_N1 \B"
$PN"ET40"121;
"DDR4_SB_CS_N2 \B"
$PN"EM40"122;
"DDR4_SB_CS_N3 \B"
$PN"EL41"123;
"DDR4_SB_CA0"
$PN"EG43"124;
"DDR4_SB_CA1"
$PN"EH44"125;
"DDR4_SB_CA2"
$PN"EM44"126;
"DDR4_SB_CA3"
$PN"EP44"127;
"DDR4_SB_CA4"
$PN"EL43"128;
"DDR4_SB_CA5"
$PN"ET42"129;
"DDR4_SB_CA6"
$PN"EK42"130;
"DDR4_SA_PAR"
$PN"EE43"131;
"DDR4_SA_ECC0"
$PN"EM57"63;
"DDR4_SA_ECC1"
$PN"EL56"62;
"DDR4_SA_ECC2"
$PN"EP57"61;
"DDR4_SA_ECC3"
$PN"ER56"60;
"DDR4_SA_ECC4"
$PN"EL54"59;
"DDR4_SA_ECC5"
$PN"EM53"58;
"DDR4_SA_ECC6"
$PN"ER54"57;
"DDR4_SA_ECC7"
$PN"EP53"56;
"DDR4_SA_DQS_DP0"
$PN"EN76"132;
"DDR4_SA_DQS_DP1"
$PN"EE70"133;
"DDR4_SA_DQS_DP2"
$PN"EL68"134;
"DDR4_SA_DQS_DP3"
$PN"EM61"135;
"DDR4_SA_DQS_DP4"
$PN"EK55"136;
"DDR4_SA_DQS_DP5"
$PN"EN74"137;
"DDR4_SA_DQS_DP6"
$PN"EG70"138;
"DDR4_SA_DQS_DP7"
$PN"EM67"139;
"DDR4_SA_DQS_DP8"
$PN"EP61"140;
"DDR4_SA_DQS_DP9"
$PN"EP55"141;
"DDR4_SA_DQS_DN0 \B"
$PN"EP75"142;
"DDR4_SA_DQS_DN1 \B"
$PN"EC70"143;
"DDR4_SA_DQS_DN2 \B"
$PN"EK67"144;
"DDR4_SA_DQS_DN3 \B"
$PN"EK61"145;
"DDR4_SA_DQS_DN4 \B"
$PN"EM55"146;
"DDR4_SA_DQS_DN5 \B"
$PN"EM75"147;
"DDR4_SA_DQS_DN6 \B"
$PN"EJ70"148;
"DDR4_SA_DQS_DN7 \B"
$PN"EN68"149;
"DDR4_SA_DQS_DN8 \B"
$PN"ET61"150;
"DDR4_SA_DQS_DN9 \B"
$PN"ET55"151;
"DDR4_SA_DQ0"
$PN"EL78"55;
"DDR4_SA_DQ1"
$PN"EM77"54;
"DDR4_SA_DQ2"
$PN"EP79"53;
"DDR4_SA_DQ3"
$PN"ER76"52;
"DDR4_SA_DQ4"
$PN"EL74"51;
"DDR4_SA_DQ5"
$PN"EK73"50;
"DDR4_SA_DQ6"
$PN"EP73"49;
"DDR4_SA_DQ7"
$PN"ER72"48;
"DDR4_SA_DQ8"
$PN"EE72"47;
"DDR4_SA_DQ9"
$PN"ED71"46;
"DDR4_SA_DQ10"
$PN"EG72"45;
"DDR4_SA_DQ11"
$PN"EH71"44;
"DDR4_SA_DQ12"
$PN"ED69"43;
"DDR4_SA_DQ13"
$PN"EE68"42;
"DDR4_SA_DQ14"
$PN"EH69"41;
"DDR4_SA_DQ15"
$PN"EG68"40;
"DDR4_SA_DQ16"
$PN"EM71"39;
"DDR4_SA_DQ17"
$PN"EM69"38;
"DDR4_SA_DQ18"
$PN"EN70"37;
"DDR4_SA_DQ19"
$PN"ER68"17;
"DDR4_SA_DQ20"
$PN"ER66"16;
"DDR4_SA_DQ21"
$PN"EM65"15;
"DDR4_SA_DQ22"
$PN"EL66"36;
"DDR4_SA_DQ23"
$PN"EP65"35;
"DDR4_SA_DQ24"
$PN"EM63"34;
"DDR4_SA_DQ25"
$PN"EL62"33;
"DDR4_SA_DQ26"
$PN"EP63"32;
"DDR4_SA_DQ27"
$PN"ER62"31;
"DDR4_SA_DQ28"
$PN"EL60"30;
"DDR4_SA_DQ29"
$PN"EM59"29;
"DDR4_SA_DQ30"
$PN"ER60"28;
"DDR4_SA_DQ31"
$PN"EP59"27;
"DDR4_SA_CS_N0 \B"
$PN"EP51"152;
"DDR4_SA_CS_N1 \B"
$PN"ET51"153;
"DDR4_SA_CS_N2 \B"
$PN"EM51"154;
"DDR4_SA_CS_N3 \B"
$PN"EL50"155;
"DDR4_SA_CA0"
$PN"EP49"156;
"DDR4_SA_CA1"
$PN"ET49"157;
"DDR4_SA_CA2"
$PN"EK49"158;
"DDR4_SA_CA3"
$PN"EL48"159;
"DDR4_SA_CA4"
$PN"EM47"160;
"DDR4_SA_CA5"
$PN"EP47"161;
"DDR4_SA_CA6"
$PN"ED44"162;
"DDR4_CLK_DP0"
$PN"EG45"26;
"DDR4_CLK_DP1"
$PN"EC45"25;
"DDR4_CLK_DN0 \B"
$PN"EJ45"24;
"DDR4_CLK_DN1 \B"
$PN"EE45"23;
"DDR4_B_RSP0"
$PN"DF44"163;
"DDR4_B_RSP1"
$PN"DG43"164;
"DDR4_A_RSP0"
$PN"DD44"165;
"DDR4_A_RSP1"
$PN"DC43"166;
"DDR4_ALERT_N \B"
$PN"CY47"167;
%"TAP"
"1","(-700,450)","2","standard","I17";
;
CDS_LIB"standard"
BODY_TYPE"PLUMBING"
HDL_TAP"TRUE";
"B \NAC \NWC"10;
"S \NAC"
BN"0"90;
%"TAP"
"1","(-700,550)","2","standard","I18";
;
CDS_LIB"standard"
BODY_TYPE"PLUMBING"
HDL_TAP"TRUE";
"B \NAC \NWC"10;
"S \NAC"
BN"2"88;
%"TAP"
"1","(-700,500)","2","standard","I19";
;
CDS_LIB"standard"
BODY_TYPE"PLUMBING"
HDL_TAP"TRUE";
"B \NAC \NWC"10;
"S \NAC"
BN"1"89;
%"TAP"
"1","(-700,600)","2","standard","I20";
;
CDS_LIB"standard"
BODY_TYPE"PLUMBING"
HDL_TAP"TRUE";
"B \NAC \NWC"10;
"S \NAC"
BN"3"87;
%"TAP"
"1","(-700,700)","2","standard","I21";
;
CDS_LIB"standard"
BODY_TYPE"PLUMBING"
HDL_TAP"TRUE";
"B \NAC \NWC"10;
"S \NAC"
BN"5"85;
%"TAP"
"1","(-700,650)","2","standard","I22";
;
CDS_LIB"standard"
BODY_TYPE"PLUMBING"
HDL_TAP"TRUE";
"B \NAC \NWC"10;
"S \NAC"
BN"4"86;
%"TAP"
"1","(-700,800)","2","standard","I23";
;
CDS_LIB"standard"
BODY_TYPE"PLUMBING"
HDL_TAP"TRUE";
"B \NAC \NWC"10;
"S \NAC"
BN"7"83;
%"TAP"
"1","(-700,750)","2","standard","I24";
;
CDS_LIB"standard"
BODY_TYPE"PLUMBING"
HDL_TAP"TRUE";
"B \NAC \NWC"10;
"S \NAC"
BN"6"84;
%"TAP"
"1","(-700,850)","2","standard","I25";
;
CDS_LIB"standard"
BODY_TYPE"PLUMBING"
HDL_TAP"TRUE";
"B \NAC \NWC"10;
"S \NAC"
BN"8"82;
%"TAP"
"1","(-700,950)","2","standard","I26";
;
CDS_LIB"standard"
BODY_TYPE"PLUMBING"
HDL_TAP"TRUE";
"B \NAC \NWC"10;
"S \NAC"
BN"10"80;
%"TAP"
"1","(-700,900)","2","standard","I27";
;
CDS_LIB"standard"
BODY_TYPE"PLUMBING"
HDL_TAP"TRUE";
"B \NAC \NWC"10;
"S \NAC"
BN"9"81;
%"TAP"
"1","(-700,1050)","2","standard","I28";
;
CDS_LIB"standard"
BODY_TYPE"PLUMBING"
HDL_TAP"TRUE";
"B \NAC \NWC"10;
"S \NAC"
BN"12"78;
%"TAP"
"1","(-700,1000)","2","standard","I29";
;
CDS_LIB"standard"
BODY_TYPE"PLUMBING"
HDL_TAP"TRUE";
"B \NAC \NWC"10;
"S \NAC"
BN"11"79;
%"TAP"
"1","(-700,-200)","2","standard","I3";
;
CDS_LIB"standard"
BODY_TYPE"PLUMBING"
HDL_TAP"TRUE";
"B \NAC \NWC"14;
"S \NAC"
BN"0"24;
%"TAP"
"1","(-700,1100)","2","standard","I30";
;
CDS_LIB"standard"
BODY_TYPE"PLUMBING"
HDL_TAP"TRUE";
"B \NAC \NWC"10;
"S \NAC"
BN"13"77;
%"TAP"
"1","(-700,1200)","2","standard","I31";
;
CDS_LIB"standard"
BODY_TYPE"PLUMBING"
HDL_TAP"TRUE";
"B \NAC \NWC"10;
"S \NAC"
BN"15"75;
%"TAP"
"1","(-700,1150)","2","standard","I32";
;
CDS_LIB"standard"
BODY_TYPE"PLUMBING"
HDL_TAP"TRUE";
"B \NAC \NWC"10;
"S \NAC"
BN"14"76;
%"TAP"
"1","(-700,1250)","2","standard","I33";
;
CDS_LIB"standard"
BODY_TYPE"PLUMBING"
HDL_TAP"TRUE";
"B \NAC \NWC"10;
"S \NAC"
BN"16"74;
%"TAP"
"1","(-700,1350)","2","standard","I34";
;
CDS_LIB"standard"
BODY_TYPE"PLUMBING"
HDL_TAP"TRUE";
"B \NAC \NWC"10;
"S \NAC"
BN"18"72;
%"TAP"
"1","(-700,1300)","2","standard","I35";
;
CDS_LIB"standard"
BODY_TYPE"PLUMBING"
HDL_TAP"TRUE";
"B \NAC \NWC"10;
"S \NAC"
BN"17"73;
%"TAP"
"1","(-700,1450)","2","standard","I36";
;
CDS_LIB"standard"
BODY_TYPE"PLUMBING"
HDL_TAP"TRUE";
"B \NAC \NWC"10;
"S \NAC"
BN"20"70;
%"TAP"
"1","(-700,1400)","2","standard","I37";
;
CDS_LIB"standard"
BODY_TYPE"PLUMBING"
HDL_TAP"TRUE";
"B \NAC \NWC"10;
"S \NAC"
BN"19"71;
%"TAP"
"1","(-700,1500)","2","standard","I38";
;
CDS_LIB"standard"
BODY_TYPE"PLUMBING"
HDL_TAP"TRUE";
"B \NAC \NWC"10;
"S \NAC"
BN"21"69;
%"TAP"
"1","(-700,1600)","2","standard","I39";
;
CDS_LIB"standard"
BODY_TYPE"PLUMBING"
HDL_TAP"TRUE";
"B \NAC \NWC"10;
"S \NAC"
BN"23"67;
%"TAP"
"1","(-700,-150)","2","standard","I4";
;
CDS_LIB"standard"
BODY_TYPE"PLUMBING"
HDL_TAP"TRUE";
"B \NAC \NWC"14;
"S \NAC"
BN"1"23;
%"TAP"
"1","(-700,1550)","2","standard","I40";
;
CDS_LIB"standard"
BODY_TYPE"PLUMBING"
HDL_TAP"TRUE";
"B \NAC \NWC"10;
"S \NAC"
BN"22"68;
%"TAP"
"1","(-700,1700)","2","standard","I41";
;
CDS_LIB"standard"
BODY_TYPE"PLUMBING"
HDL_TAP"TRUE";
"B \NAC \NWC"10;
"S \NAC"
BN"25"19;
%"TAP"
"1","(-700,1650)","2","standard","I42";
;
CDS_LIB"standard"
BODY_TYPE"PLUMBING"
HDL_TAP"TRUE";
"B \NAC \NWC"10;
"S \NAC"
BN"24"18;
%"TAP"
"1","(-700,1750)","2","standard","I43";
;
CDS_LIB"standard"
BODY_TYPE"PLUMBING"
HDL_TAP"TRUE";
"B \NAC \NWC"10;
"S \NAC"
BN"26"20;
%"TAP"
"1","(-700,1850)","2","standard","I44";
;
CDS_LIB"standard"
BODY_TYPE"PLUMBING"
HDL_TAP"TRUE";
"B \NAC \NWC"10;
"S \NAC"
BN"28"22;
%"TAP"
"1","(-700,1800)","2","standard","I45";
;
CDS_LIB"standard"
BODY_TYPE"PLUMBING"
HDL_TAP"TRUE";
"B \NAC \NWC"10;
"S \NAC"
BN"27"21;
%"TAP"
"1","(-700,1950)","2","standard","I46";
;
CDS_LIB"standard"
BODY_TYPE"PLUMBING"
HDL_TAP"TRUE";
"B \NAC \NWC"10;
"S \NAC"
BN"30"65;
%"TAP"
"1","(-700,1900)","2","standard","I47";
;
CDS_LIB"standard"
BODY_TYPE"PLUMBING"
HDL_TAP"TRUE";
"B \NAC \NWC"10;
"S \NAC"
BN"29"66;
%"TAP"
"1","(-700,2000)","2","standard","I48";
;
CDS_LIB"standard"
BODY_TYPE"PLUMBING"
HDL_TAP"TRUE";
"B \NAC \NWC"10;
"S \NAC"
BN"31"64;
%"TAP"
"1","(-700,2100)","2","standard","I49";
;
CDS_LIB"standard"
BODY_TYPE"PLUMBING"
HDL_TAP"TRUE";
"B \NAC \NWC"11;
"S \NAC"
BN"1"62;
%"TAP"
"1","(-700,-50)","2","standard","I5";
;
CDS_LIB"standard"
BODY_TYPE"PLUMBING"
HDL_TAP"TRUE";
"B \NAC \NWC"13;
"S \NAC"
BN"1"25;
%"TAP"
"1","(-700,2050)","2","standard","I50";
;
CDS_LIB"standard"
BODY_TYPE"PLUMBING"
HDL_TAP"TRUE";
"B \NAC \NWC"11;
"S \NAC"
BN"0"63;
%"TAP"
"1","(-700,2250)","2","standard","I53";
;
CDS_LIB"standard"
BODY_TYPE"PLUMBING"
HDL_TAP"TRUE";
"B \NAC \NWC"11;
"S \NAC"
BN"4"59;
%"TAP"
"1","(-700,2200)","2","standard","I54";
;
CDS_LIB"standard"
BODY_TYPE"PLUMBING"
HDL_TAP"TRUE";
"B \NAC \NWC"11;
"S \NAC"
BN"3"60;
%"TAP"
"1","(-700,2150)","2","standard","I55";
;
CDS_LIB"standard"
BODY_TYPE"PLUMBING"
HDL_TAP"TRUE";
"B \NAC \NWC"11;
"S \NAC"
BN"2"61;
%"TAP"
"1","(-700,2350)","2","standard","I56";
;
CDS_LIB"standard"
BODY_TYPE"PLUMBING"
HDL_TAP"TRUE";
"B \NAC \NWC"11;
"S \NAC"
BN"6"57;
%"TAP"
"1","(-700,2300)","2","standard","I57";
;
CDS_LIB"standard"
BODY_TYPE"PLUMBING"
HDL_TAP"TRUE";
"B \NAC \NWC"11;
"S \NAC"
BN"5"58;
%"TAP"
"1","(-700,2400)","2","standard","I58";
;
CDS_LIB"standard"
BODY_TYPE"PLUMBING"
HDL_TAP"TRUE";
"B \NAC \NWC"11;
"S \NAC"
BN"7"56;
%"TAP"
"1","(-700,2450)","2","standard","I59";
;
CDS_LIB"standard"
BODY_TYPE"PLUMBING"
HDL_TAP"TRUE";
"B \NAC \NWC"12;
"S \NAC"
BN"0"55;
%"TAP"
"1","(-700,-100)","2","standard","I6";
;
CDS_LIB"standard"
BODY_TYPE"PLUMBING"
HDL_TAP"TRUE";
"B \NAC \NWC"13;
"S \NAC"
BN"0"26;
%"TAP"
"1","(-700,2500)","2","standard","I60";
;
CDS_LIB"standard"
BODY_TYPE"PLUMBING"
HDL_TAP"TRUE";
"B \NAC \NWC"12;
"S \NAC"
BN"1"54;
%"TAP"
"1","(-700,2600)","2","standard","I61";
;
CDS_LIB"standard"
BODY_TYPE"PLUMBING"
HDL_TAP"TRUE";
"B \NAC \NWC"12;
"S \NAC"
BN"3"52;
%"TAP"
"1","(-700,2550)","2","standard","I62";
;
CDS_LIB"standard"
BODY_TYPE"PLUMBING"
HDL_TAP"TRUE";
"B \NAC \NWC"12;
"S \NAC"
BN"2"53;
%"TAP"
"1","(-700,2650)","2","standard","I63";
;
CDS_LIB"standard"
BODY_TYPE"PLUMBING"
HDL_TAP"TRUE";
"B \NAC \NWC"12;
"S \NAC"
BN"4"51;
%"TAP"
"1","(-700,2750)","2","standard","I64";
;
CDS_LIB"standard"
BODY_TYPE"PLUMBING"
HDL_TAP"TRUE";
"B \NAC \NWC"12;
"S \NAC"
BN"6"49;
%"TAP"
"1","(-700,2700)","2","standard","I65";
;
CDS_LIB"standard"
BODY_TYPE"PLUMBING"
HDL_TAP"TRUE";
"B \NAC \NWC"12;
"S \NAC"
BN"5"50;
%"TAP"
"1","(-700,2850)","2","standard","I66";
;
CDS_LIB"standard"
BODY_TYPE"PLUMBING"
HDL_TAP"TRUE";
"B \NAC \NWC"12;
"S \NAC"
BN"8"47;
%"TAP"
"1","(-700,2800)","2","standard","I67";
;
CDS_LIB"standard"
BODY_TYPE"PLUMBING"
HDL_TAP"TRUE";
"B \NAC \NWC"12;
"S \NAC"
BN"7"48;
%"TAP"
"1","(-700,2900)","2","standard","I68";
;
CDS_LIB"standard"
BODY_TYPE"PLUMBING"
HDL_TAP"TRUE";
"B \NAC \NWC"12;
"S \NAC"
BN"9"46;
%"TAP"
"1","(-700,3000)","2","standard","I69";
;
CDS_LIB"standard"
BODY_TYPE"PLUMBING"
HDL_TAP"TRUE";
"B \NAC \NWC"12;
"S \NAC"
BN"11"44;
%"TAP"
"1","(-700,50)","2","standard","I7";
;
CDS_LIB"standard"
BODY_TYPE"PLUMBING"
HDL_TAP"TRUE";
"B \NAC \NWC"9;
"S \NAC"
BN"0"98;
%"TAP"
"1","(-700,2950)","2","standard","I70";
;
CDS_LIB"standard"
BODY_TYPE"PLUMBING"
HDL_TAP"TRUE";
"B \NAC \NWC"12;
"S \NAC"
BN"10"45;
%"TAP"
"1","(-700,3100)","2","standard","I71";
;
CDS_LIB"standard"
BODY_TYPE"PLUMBING"
HDL_TAP"TRUE";
"B \NAC \NWC"12;
"S \NAC"
BN"13"42;
%"TAP"
"1","(-700,3050)","2","standard","I72";
;
CDS_LIB"standard"
BODY_TYPE"PLUMBING"
HDL_TAP"TRUE";
"B \NAC \NWC"12;
"S \NAC"
BN"12"43;
%"TAP"
"1","(-700,3150)","2","standard","I73";
;
CDS_LIB"standard"
BODY_TYPE"PLUMBING"
HDL_TAP"TRUE";
"B \NAC \NWC"12;
"S \NAC"
BN"14"41;
%"TAP"
"1","(-700,3250)","2","standard","I74";
;
CDS_LIB"standard"
BODY_TYPE"PLUMBING"
HDL_TAP"TRUE";
"B \NAC \NWC"12;
"S \NAC"
BN"16"39;
%"TAP"
"1","(-700,3200)","2","standard","I75";
;
CDS_LIB"standard"
BODY_TYPE"PLUMBING"
HDL_TAP"TRUE";
"B \NAC \NWC"12;
"S \NAC"
BN"15"40;
%"TAP"
"1","(-700,3300)","2","standard","I76";
;
CDS_LIB"standard"
BODY_TYPE"PLUMBING"
HDL_TAP"TRUE";
"B \NAC \NWC"12;
"S \NAC"
BN"17"38;
%"TAP"
"1","(-700,3400)","2","standard","I77";
;
CDS_LIB"standard"
BODY_TYPE"PLUMBING"
HDL_TAP"TRUE";
"B \NAC \NWC"12;
"S \NAC"
BN"19"17;
%"TAP"
"1","(-700,3350)","2","standard","I78";
;
CDS_LIB"standard"
BODY_TYPE"PLUMBING"
HDL_TAP"TRUE";
"B \NAC \NWC"12;
"S \NAC"
BN"18"37;
%"TAP"
"1","(-700,3500)","2","standard","I79";
;
CDS_LIB"standard"
BODY_TYPE"PLUMBING"
HDL_TAP"TRUE";
"B \NAC \NWC"12;
"S \NAC"
BN"21"15;
%"TAP"
"1","(-700,100)","2","standard","I8";
;
CDS_LIB"standard"
BODY_TYPE"PLUMBING"
HDL_TAP"TRUE";
"B \NAC \NWC"9;
"S \NAC"
BN"1"97;
%"TAP"
"1","(-700,3450)","2","standard","I80";
;
CDS_LIB"standard"
BODY_TYPE"PLUMBING"
HDL_TAP"TRUE";
"B \NAC \NWC"12;
"S \NAC"
BN"20"16;
%"TAP"
"1","(-700,3550)","2","standard","I81";
;
CDS_LIB"standard"
BODY_TYPE"PLUMBING"
HDL_TAP"TRUE";
"B \NAC \NWC"12;
"S \NAC"
BN"22"36;
%"TAP"
"1","(-700,3600)","2","standard","I82";
;
CDS_LIB"standard"
BODY_TYPE"PLUMBING"
HDL_TAP"TRUE";
"B \NAC \NWC"12;
"S \NAC"
BN"23"35;
%"TAP"
"1","(-700,3650)","2","standard","I83";
;
CDS_LIB"standard"
BODY_TYPE"PLUMBING"
HDL_TAP"TRUE";
"B \NAC \NWC"12;
"S \NAC"
BN"24"34;
%"TAP"
"1","(-700,3750)","2","standard","I84";
;
CDS_LIB"standard"
BODY_TYPE"PLUMBING"
HDL_TAP"TRUE";
"B \NAC \NWC"12;
"S \NAC"
BN"26"32;
%"TAP"
"1","(-700,3700)","2","standard","I85";
;
CDS_LIB"standard"
BODY_TYPE"PLUMBING"
HDL_TAP"TRUE";
"B \NAC \NWC"12;
"S \NAC"
BN"25"33;
%"TAP"
"1","(-700,3800)","2","standard","I86";
;
CDS_LIB"standard"
BODY_TYPE"PLUMBING"
HDL_TAP"TRUE";
"B \NAC \NWC"12;
"S \NAC"
BN"27"31;
%"TAP"
"1","(-700,3900)","2","standard","I87";
;
CDS_LIB"standard"
BODY_TYPE"PLUMBING"
HDL_TAP"TRUE";
"B \NAC \NWC"12;
"S \NAC"
BN"29"29;
%"TAP"
"1","(-700,3850)","2","standard","I88";
;
CDS_LIB"standard"
BODY_TYPE"PLUMBING"
HDL_TAP"TRUE";
"B \NAC \NWC"12;
"S \NAC"
BN"28"30;
%"TAP"
"1","(-700,3950)","2","standard","I89";
;
CDS_LIB"standard"
BODY_TYPE"PLUMBING"
HDL_TAP"TRUE";
"B \NAC \NWC"12;
"S \NAC"
BN"30"28;
%"TAP"
"1","(-700,4000)","2","standard","I90";
;
CDS_LIB"standard"
BODY_TYPE"PLUMBING"
HDL_TAP"TRUE";
"B \NAC \NWC"12;
"S \NAC"
BN"31"27;
%"TAP"
"1","(2725,350)","0","standard","I97";
;
CDS_LIB"standard"
BODY_TYPE"PLUMBING"
HDL_TAP"TRUE";
"B \NAC \NWC"6;
"S \NAC"
BN"2"122;
%"TAP"
"1","(2725,300)","0","standard","I98";
;
CDS_LIB"standard"
BODY_TYPE"PLUMBING"
HDL_TAP"TRUE";
"B \NAC \NWC"6;
"S \NAC"
BN"1"121;
%"TAP"
"1","(2725,250)","0","standard","I99";
;
CDS_LIB"standard"
BODY_TYPE"PLUMBING"
HDL_TAP"TRUE";
"B \NAC \NWC"6;
"S \NAC"
BN"0"120;
END.
